(kicad_pcb
	(version 20260206)
	(generator "pcbnew")
	(generator_version "10.0")
	(general
		(thickness 1.6)
		(legacy_teardrops no)
	)
	(paper "A4")
	(title_block
		(title "baseboard — 13948-1b.1110WZS1818.brd")
		(comment 1 "Honey Badger (Wiwynn) / footprints 2446-2453 of 2523")
	)
	(layers
		(0 "F.Cu" signal "TOP")
		(4 "In1.Cu" signal "L2GND")
		(6 "In2.Cu" signal "L3")
		(8 "In3.Cu" signal "L4VCC")
		(10 "In4.Cu" signal "L5VCC")
		(12 "In5.Cu" signal "L6")
		(14 "In6.Cu" signal "L7GND")
		(2 "B.Cu" signal "BOTTOM")
		(9 "F.Adhes" user "F.Adhesive")
		(11 "B.Adhes" user "B.Adhesive")
		(13 "F.Paste" user "Package Geometry/Pastemask Top")
		(15 "B.Paste" user "Package Geometry/Pastemask Bottom")
		(5 "F.SilkS" user "Ref Des/Silkscreen Top")
		(7 "B.SilkS" user "Ref Des/Silkscreen Bottom")
		(1 "F.Mask" user "Board Geometry/Soldermask Top")
		(3 "B.Mask" user "Board Geometry/Soldermask Bottom")
		(17 "Dwgs.User" user "User.Drawings")
		(19 "Cmts.User" user "User.Comments")
		(21 "Eco1.User" user "User.Eco1")
		(23 "Eco2.User" user "User.Eco2")
		(25 "Edge.Cuts" user "Board Geometry/Outline")
		(27 "Margin" user)
		(31 "F.CrtYd" user "Package Geometry/Place Bound Top")
		(29 "B.CrtYd" user "Package Geometry/Place Bound Bottom")
		(35 "F.Fab" user "Ref Des/Assembly Top")
		(33 "B.Fab" user "Ref Des/Assembly Bottom")
	)
	(footprint ""
		(layer "B.Cu")
		(at 124.09297 -104.394)
		(property "Reference" "SC1178"
			(at 0 0 0)
			(layer "B.SilkS")
			(hide yes)
			(effects
				(font
					(size 1.27 1.27)
				)
				(justify mirror)
			)
		)
		(property "Value" "SC1U6D3V1MX-GP"
			(at -1.9177 2.0193 0)
			(unlocked yes)
			(layer "B.Fab")
			(hide yes)
			(effects
				(font
					(size 1.016 1.016)
					(thickness 0.1524)
				)
				(justify mirror)
			)
		)
		(property "Device Type" "C0201H14"
			(at -1.9177 0.4953 0)
			(unlocked yes)
			(layer "B.Fab")
			(hide yes)
			(effects
				(font
					(size 1.016 1.016)
					(thickness 0.1524)
				)
				(justify mirror)
			)
		)
		(duplicate_pad_numbers_are_jumpers no)
		(fp_rect
			(start 0.1524 0.3048)
			(end -0.1524 -0.3048)
			(stroke
				(width 0)
				(type default)
			)
			(fill no)
			(layer "B.CrtYd")
		)
		(fp_poly
			(pts
				(xy 0.2794 0.6477) (xy 0.2794 -0.6477) (xy -0.2794 -0.6477) (xy -0.2794 -0.1905) (xy -0.1524 -0.1905)
				(xy -0.1524 -0.3048) (xy 0.1524 -0.3048) (xy 0.1524 0.3048) (xy -0.1524 0.3048) (xy -0.1524 -0.1778)
				(xy -0.2794 -0.1778) (xy -0.2794 0.6477)
			)
			(stroke
				(width 0)
				(type default)
			)
			(fill no)
			(layer "B.CrtYd")
		)
		(fp_rect
			(start 0.2794 0.6477)
			(end -0.2794 -0.6477)
			(stroke
				(width 0)
				(type default)
			)
			(fill no)
			(layer "B.Fab")
		)
		(pad "1" smd custom
			(at 0 -0.2794 180)
			(size 0.0762 0.0762)
			(layers "B.Cu" "B.Mask" "B.Paste")
			(net "GB_VDDA")
			(options
				(clearance outline)
				(anchor circle)
			)
			(primitives
				(gr_poly
					(pts
						(arc
							(start 0.1524 0.127)
							(mid 0.137521 0.162921)
							(end 0.1016 0.1778)
						)
						(arc
							(start -0.1016 0.1778)
							(mid -0.137521 0.162921)
							(end -0.1524 0.127)
						)
						(arc
							(start -0.1524 -0.127)
							(mid -0.137521 -0.162921)
							(end -0.1016 -0.1778)
						)
						(arc
							(start 0.1016 -0.1778)
							(mid 0.137521 -0.162921)
							(end 0.1524 -0.127)
						)
					)
					(width 0)
					(fill yes)
				)
			)
		)
		(pad "2" smd custom
			(at 0 0.2794 180)
			(size 0.0762 0.0762)
			(layers "B.Cu" "B.Mask" "B.Paste")
			(net "GND")
			(options
				(clearance outline)
				(anchor circle)
			)
			(primitives
				(gr_poly
					(pts
						(arc
							(start 0.1524 0.127)
							(mid 0.137521 0.162921)
							(end 0.1016 0.1778)
						)
						(arc
							(start -0.1016 0.1778)
							(mid -0.137521 0.162921)
							(end -0.1524 0.127)
						)
						(arc
							(start -0.1524 -0.127)
							(mid -0.137521 -0.162921)
							(end -0.1016 -0.1778)
						)
						(arc
							(start 0.1016 -0.1778)
							(mid 0.137521 -0.162921)
							(end 0.1524 -0.127)
						)
					)
					(width 0)
					(fill yes)
				)
			)
		)
	)
	(footprint ""
		(layer "B.Cu")
		(at 54.30393 -76.761086)
		(property "Reference" "SC1281"
			(at 0 0 0)
			(layer "B.SilkS")
			(hide yes)
			(effects
				(font
					(size 1.27 1.27)
				)
				(justify mirror)
			)
		)
		(property "Value" "SCD01U50V2KX-1GP"
			(at -1.1811 -2.7051 0)
			(unlocked yes)
			(layer "B.Fab")
			(hide yes)
			(effects
				(font
					(size 1.016 1.016)
					(thickness 0.1524)
				)
				(justify mirror)
			)
		)
		(property "Device Type" "C402H22"
			(at -1.1811 -4.2291 0)
			(unlocked yes)
			(layer "B.Fab")
			(hide yes)
			(effects
				(font
					(size 1.016 1.016)
					(thickness 0.1524)
				)
				(justify mirror)
			)
		)
		(duplicate_pad_numbers_are_jumpers no)
		(fp_rect
			(start 0.4318 0.9525)
			(end -0.4318 -0.9525)
			(stroke
				(width 0)
				(type default)
			)
			(fill no)
			(layer "B.CrtYd")
		)
		(fp_rect
			(start 0.4318 0.9525)
			(end -0.4318 -0.9525)
			(stroke
				(width 0)
				(type default)
			)
			(fill no)
			(layer "B.Fab")
		)
		(pad "1" smd custom
			(at 0 -0.4445 180)
			(size 0.1524 0.1524)
			(layers "B.Cu" "B.Mask" "B.Paste")
			(net "SAS_EXP2CONN_RX_N_23")
			(options
				(clearance outline)
				(anchor circle)
			)
			(primitives
				(gr_poly
					(pts
						(arc
							(start 0.3048 0.2032)
							(mid 0.275042 0.275042)
							(end 0.2032 0.3048)
						)
						(arc
							(start -0.2032 0.3048)
							(mid -0.275042 0.275042)
							(end -0.3048 0.2032)
						)
						(arc
							(start -0.3048 -0.2032)
							(mid -0.275042 -0.275042)
							(end -0.2032 -0.3048)
						)
						(arc
							(start 0.2032 -0.3048)
							(mid 0.275042 -0.275042)
							(end 0.3048 -0.2032)
						)
					)
					(width 0)
					(fill yes)
				)
			)
		)
		(pad "2" smd custom
			(at 0 0.4445 180)
			(size 0.1524 0.1524)
			(layers "B.Cu" "B.Mask" "B.Paste")
			(net "MINI_RX_N_23")
			(options
				(clearance outline)
				(anchor circle)
			)
			(primitives
				(gr_poly
					(pts
						(arc
							(start 0.3048 0.2032)
							(mid 0.275042 0.275042)
							(end 0.2032 0.3048)
						)
						(arc
							(start -0.2032 0.3048)
							(mid -0.275042 0.275042)
							(end -0.3048 0.2032)
						)
						(arc
							(start -0.3048 -0.2032)
							(mid -0.275042 -0.275042)
							(end -0.2032 -0.3048)
						)
						(arc
							(start 0.2032 -0.3048)
							(mid 0.275042 -0.275042)
							(end 0.3048 -0.2032)
						)
					)
					(width 0)
					(fill yes)
				)
			)
		)
	)
	(footprint ""
		(layer "B.Cu")
		(at 349.5802 -71.8058 180)
		(property "Reference" "R293"
			(at 0 0 0)
			(layer "B.SilkS")
			(hide yes)
			(effects
				(font
					(size 1.27 1.27)
				)
				(justify mirror)
			)
		)
		(property "Value" "0R0402-PAD-1-GP"
			(at -0.064008 -3.993896 180)
			(unlocked yes)
			(layer "B.Fab")
			(hide yes)
			(effects
				(font
					(size 1.016 1.016)
					(thickness 0.1524)
				)
				(justify mirror)
			)
		)
		(property "Device Type" "0R0402-PAD"
			(at -0.064008 -5.517896 180)
			(unlocked yes)
			(layer "B.Fab")
			(hide yes)
			(effects
				(font
					(size 1.016 1.016)
					(thickness 0.1524)
				)
				(justify mirror)
			)
		)
		(duplicate_pad_numbers_are_jumpers no)
		(fp_line
			(start 0.508 -0.9398)
			(end 0.508 0.9398)
			(stroke
				(width 0.1524)
				(type default)
			)
			(layer "B.SilkS")
		)
		(fp_line
			(start -0.508 -0.9398)
			(end 0.508 -0.9398)
			(stroke
				(width 0.1524)
				(type default)
			)
			(layer "B.SilkS")
		)
		(fp_rect
			(start 0.508 0.9398)
			(end -0.508 -0.9398)
			(stroke
				(width 0)
				(type default)
			)
			(fill no)
			(layer "B.CrtYd")
		)
		(fp_rect
			(start 0.508 0.9398)
			(end -0.508 -0.9398)
			(stroke
				(width 0)
				(type default)
			)
			(fill no)
			(layer "B.Fab")
		)
		(pad "1" smd custom
			(at 0 -0.4445)
			(size 0.1397 0.1397)
			(layers "B.Cu" "B.Mask" "B.Paste")
			(net "ROMD1_R")
			(options
				(clearance outline)
				(anchor circle)
			)
			(primitives
				(gr_poly
					(pts
						(xy -0.2794 -0.3683)
						(arc
							(start -0.2794 0.2667)
							(mid -0.249642 0.338542)
							(end -0.1778 0.3683)
						)
						(arc
							(start 0.1778 0.3683)
							(mid 0.249642 0.338542)
							(end 0.2794 0.2667)
						)
						(xy 0.2794 -0.3683)
					)
					(width 0)
					(fill yes)
				)
			)
		)
		(pad "2" smd custom
			(at 0 0.4445)
			(size 0.1397 0.1397)
			(layers "B.Cu" "B.Mask" "B.Paste")
			(net "ROMD1")
			(options
				(clearance outline)
				(anchor circle)
			)
			(primitives
				(gr_poly
					(pts
						(arc
							(start -0.1778 -0.3683)
							(mid -0.249642 -0.338542)
							(end -0.2794 -0.2667)
						)
						(xy -0.2794 0.3683) (xy 0.2794 0.3683)
						(arc
							(start 0.2794 -0.2667)
							(mid 0.249642 -0.338542)
							(end 0.1778 -0.3683)
						)
					)
					(width 0)
					(fill yes)
				)
			)
		)
	)
	(footprint ""
		(layer "B.Cu")
		(at 110.807246 -51.42992 -90)
		(property "Reference" "SC1006"
			(at 0 0 90)
			(layer "B.SilkS")
			(hide yes)
			(effects
				(font
					(size 1.27 1.27)
				)
				(justify mirror)
			)
		)
		(property "Value" "SCD1U16V2KX-3GP"
			(at -1.1811 -2.7051 270)
			(unlocked yes)
			(layer "B.Fab")
			(hide yes)
			(effects
				(font
					(size 1.016 1.016)
					(thickness 0.1524)
				)
				(justify mirror)
			)
		)
		(property "Device Type" "C402H22"
			(at -1.1811 -4.2291 270)
			(unlocked yes)
			(layer "B.Fab")
			(hide yes)
			(effects
				(font
					(size 1.016 1.016)
					(thickness 0.1524)
				)
				(justify mirror)
			)
		)
		(duplicate_pad_numbers_are_jumpers no)
		(fp_rect
			(start 0.4318 0.9525)
			(end -0.4318 -0.9525)
			(stroke
				(width 0)
				(type default)
			)
			(fill no)
			(layer "B.CrtYd")
		)
		(fp_rect
			(start 0.4318 0.9525)
			(end -0.4318 -0.9525)
			(stroke
				(width 0)
				(type default)
			)
			(fill no)
			(layer "B.Fab")
		)
		(pad "1" smd custom
			(at 0 -0.4445 90)
			(size 0.1524 0.1524)
			(layers "B.Cu" "B.Mask" "B.Paste")
			(net "P1V8_C")
			(options
				(clearance outline)
				(anchor circle)
			)
			(primitives
				(gr_poly
					(pts
						(arc
							(start 0.3048 0.2032)
							(mid 0.275042 0.275042)
							(end 0.2032 0.3048)
						)
						(arc
							(start -0.2032 0.3048)
							(mid -0.275042 0.275042)
							(end -0.3048 0.2032)
						)
						(arc
							(start -0.3048 -0.2032)
							(mid -0.275042 -0.275042)
							(end -0.2032 -0.3048)
						)
						(arc
							(start 0.2032 -0.3048)
							(mid 0.275042 -0.275042)
							(end 0.3048 -0.2032)
						)
					)
					(width 0)
					(fill yes)
				)
			)
		)
		(pad "2" smd custom
			(at 0 0.4445 90)
			(size 0.1524 0.1524)
			(layers "B.Cu" "B.Mask" "B.Paste")
			(net "GND")
			(options
				(clearance outline)
				(anchor circle)
			)
			(primitives
				(gr_poly
					(pts
						(arc
							(start 0.3048 0.2032)
							(mid 0.275042 0.275042)
							(end 0.2032 0.3048)
						)
						(arc
							(start -0.2032 0.3048)
							(mid -0.275042 0.275042)
							(end -0.3048 0.2032)
						)
						(arc
							(start -0.3048 -0.2032)
							(mid -0.275042 -0.275042)
							(end -0.2032 -0.3048)
						)
						(arc
							(start 0.2032 -0.3048)
							(mid 0.275042 -0.275042)
							(end 0.3048 -0.2032)
						)
					)
					(width 0)
					(fill yes)
				)
			)
		)
	)
	(footprint ""
		(layer "B.Cu")
		(at 114.61877 -101.3968 180)
		(property "Reference" "SC1137"
			(at 0 0 0)
			(layer "B.SilkS")
			(hide yes)
			(effects
				(font
					(size 1.27 1.27)
				)
				(justify mirror)
			)
		)
		(property "Value" "SCD1U6D3V1KX-GP"
			(at 2.8321 -1.7399 180)
			(unlocked yes)
			(layer "B.Fab")
			(hide yes)
			(effects
				(font
					(size 1.016 1.016)
					(thickness 0.1524)
				)
				(justify mirror)
			)
		)
		(property "Device Type" "C0201H13"
			(at 2.8321 -3.2639 180)
			(unlocked yes)
			(layer "B.Fab")
			(hide yes)
			(effects
				(font
					(size 1.016 1.016)
					(thickness 0.1524)
				)
				(justify mirror)
			)
		)
		(duplicate_pad_numbers_are_jumpers no)
		(fp_rect
			(start 0.2794 0.6477)
			(end -0.2794 -0.6477)
			(stroke
				(width 0)
				(type default)
			)
			(fill no)
			(layer "B.CrtYd")
		)
		(fp_rect
			(start 0.2794 0.6477)
			(end -0.2794 -0.6477)
			(stroke
				(width 0)
				(type default)
			)
			(fill no)
			(layer "B.Fab")
		)
		(pad "1" smd custom
			(at 0 -0.2794)
			(size 0.0762 0.0762)
			(layers "B.Cu" "B.Mask" "B.Paste")
			(net "GB_VDDH2")
			(options
				(clearance outline)
				(anchor circle)
			)
			(primitives
				(gr_poly
					(pts
						(arc
							(start 0.1524 0.127)
							(mid 0.137521 0.162921)
							(end 0.1016 0.1778)
						)
						(arc
							(start -0.1016 0.1778)
							(mid -0.137521 0.162921)
							(end -0.1524 0.127)
						)
						(arc
							(start -0.1524 -0.127)
							(mid -0.137521 -0.162921)
							(end -0.1016 -0.1778)
						)
						(arc
							(start 0.1016 -0.1778)
							(mid 0.137521 -0.162921)
							(end 0.1524 -0.127)
						)
					)
					(width 0)
					(fill yes)
				)
			)
		)
		(pad "2" smd custom
			(at 0 0.2794)
			(size 0.0762 0.0762)
			(layers "B.Cu" "B.Mask" "B.Paste")
			(net "GND")
			(options
				(clearance outline)
				(anchor circle)
			)
			(primitives
				(gr_poly
					(pts
						(arc
							(start 0.1524 0.127)
							(mid 0.137521 0.162921)
							(end 0.1016 0.1778)
						)
						(arc
							(start -0.1016 0.1778)
							(mid -0.137521 0.162921)
							(end -0.1524 0.127)
						)
						(arc
							(start -0.1524 -0.127)
							(mid -0.137521 -0.162921)
							(end -0.1016 -0.1778)
						)
						(arc
							(start 0.1016 -0.1778)
							(mid 0.137521 -0.162921)
							(end 0.1524 -0.127)
						)
					)
					(width 0)
					(fill yes)
				)
			)
		)
	)
	(footprint ""
		(layer "B.Cu")
		(at 127.90297 -97.917 90)
		(property "Reference" "SC1165"
			(at 0 0 90)
			(layer "B.SilkS")
			(hide yes)
			(effects
				(font
					(size 1.27 1.27)
				)
				(justify mirror)
			)
		)
		(property "Value" "SC22U6D3V5MX-2GP"
			(at 0.0762 -6.1214 90)
			(unlocked yes)
			(layer "B.Fab")
			(hide yes)
			(effects
				(font
					(size 1.016 1.016)
					(thickness 0.1524)
				)
				(justify mirror)
			)
		)
		(property "Device Type" "C805H58"
			(at 0.0762 -8.1534 90)
			(unlocked yes)
			(layer "B.Fab")
			(hide yes)
			(effects
				(font
					(size 1.016 1.016)
					(thickness 0.1524)
				)
				(justify mirror)
			)
		)
		(duplicate_pad_numbers_are_jumpers no)
		(fp_line
			(start -0.635 0)
			(end 0.635 0)
			(stroke
				(width 0.508)
				(type default)
			)
			(layer "B.SilkS")
		)
		(fp_rect
			(start 0.9652 1.778)
			(end -0.9652 -1.778)
			(stroke
				(width 0)
				(type default)
			)
			(fill no)
			(layer "B.CrtYd")
		)
		(fp_poly
			(pts
				(xy 0.9652 -1.778) (xy -0.9652 -1.778) (xy -0.9652 1.778) (xy 0.9652 1.778)
			)
			(stroke
				(width 0)
				(type default)
			)
			(fill no)
			(layer "B.Fab")
		)
		(pad "1" smd rect
			(at 0 -0.9652 270)
			(size 1.397 1.143)
			(layers "B.Cu" "B.Mask" "B.Paste")
			(net "GB_VDDA")
		)
		(pad "2" smd rect
			(at 0 0.9652 270)
			(size 1.397 1.143)
			(layers "B.Cu" "B.Mask" "B.Paste")
			(net "GND")
		)
	)
	(footprint ""
		(layer "B.Cu")
		(at 319.913 -166.878 90)
		(property "Reference" "R411"
			(at 0 0 90)
			(layer "B.SilkS")
			(hide yes)
			(effects
				(font
					(size 1.27 1.27)
				)
				(justify mirror)
			)
		)
		(property "Value" "4K7R2F-GP"
			(at -0.064008 -3.993896 90)
			(unlocked yes)
			(layer "B.Fab")
			(hide yes)
			(effects
				(font
					(size 1.016 1.016)
					(thickness 0.1524)
				)
				(justify mirror)
			)
		)
		(property "Device Type" "R402H16"
			(at -0.064008 -5.517896 90)
			(unlocked yes)
			(layer "B.Fab")
			(hide yes)
			(effects
				(font
					(size 1.016 1.016)
					(thickness 0.1524)
				)
				(justify mirror)
			)
		)
		(duplicate_pad_numbers_are_jumpers no)
		(fp_line
			(start 0.508 -0.9398)
			(end 0.508 0.9398)
			(stroke
				(width 0.1524)
				(type default)
			)
			(layer "B.SilkS")
		)
		(fp_line
			(start -0.508 -0.9398)
			(end 0.508 -0.9398)
			(stroke
				(width 0.1524)
				(type default)
			)
			(layer "B.SilkS")
		)
		(fp_rect
			(start 0.508 0.9398)
			(end -0.508 -0.9398)
			(stroke
				(width 0)
				(type default)
			)
			(fill no)
			(layer "B.CrtYd")
		)
		(fp_rect
			(start 0.508 0.9398)
			(end -0.508 -0.9398)
			(stroke
				(width 0)
				(type default)
			)
			(fill no)
			(layer "B.Fab")
		)
		(pad "1" smd custom
			(at 0 -0.4445 270)
			(size 0.1397 0.1397)
			(layers "B.Cu" "B.Mask" "B.Paste")
			(net "BMC_I2C_D_SCL")
			(options
				(clearance outline)
				(anchor circle)
			)
			(primitives
				(gr_poly
					(pts
						(arc
							(start -0.1778 0.2794)
							(mid -0.249642 0.249642)
							(end -0.2794 0.1778)
						)
						(arc
							(start -0.2794 -0.1778)
							(mid -0.249642 -0.249642)
							(end -0.1778 -0.2794)
						)
						(arc
							(start 0.1778 -0.2794)
							(mid 0.249642 -0.249642)
							(end 0.2794 -0.1778)
						)
						(arc
							(start 0.2794 0.1778)
							(mid 0.249642 0.249642)
							(end 0.1778 0.2794)
						)
					)
					(width 0)
					(fill yes)
				)
			)
		)
		(pad "2" smd custom
			(at 0 0.4445 270)
			(size 0.1397 0.1397)
			(layers "B.Cu" "B.Mask" "B.Paste")
			(net "P3V3_STBY")
			(options
				(clearance outline)
				(anchor circle)
			)
			(primitives
				(gr_poly
					(pts
						(arc
							(start -0.1778 0.2794)
							(mid -0.249642 0.249642)
							(end -0.2794 0.1778)
						)
						(arc
							(start -0.2794 -0.1778)
							(mid -0.249642 -0.249642)
							(end -0.1778 -0.2794)
						)
						(arc
							(start 0.1778 -0.2794)
							(mid 0.249642 -0.249642)
							(end 0.2794 -0.1778)
						)
						(arc
							(start 0.2794 0.1778)
							(mid 0.249642 0.249642)
							(end 0.1778 0.2794)
						)
					)
					(width 0)
					(fill yes)
				)
			)
		)
	)
	(footprint ""
		(layer "B.Cu")
		(at 104.883966 -36.957)
		(property "Reference" "STP55"
			(at 0 0 0)
			(layer "B.SilkS")
			(hide yes)
			(effects
				(font
					(size 1.27 1.27)
				)
				(justify mirror)
			)
		)
		(property "Value" "TPAD28"
			(at -0.0127 -1.8034 0)
			(unlocked yes)
			(layer "B.Fab")
			(hide yes)
			(effects
				(font
					(size 1.016 1.016)
					(thickness 0.1524)
				)
				(justify mirror)
			)
		)
		(property "Device Type" "TPAD28"
			(at -0.0127 -3.3274 0)
			(unlocked yes)
			(layer "B.Fab")
			(hide yes)
			(effects
				(font
					(size 1.016 1.016)
					(thickness 0.1524)
				)
				(justify mirror)
			)
		)
		(duplicate_pad_numbers_are_jumpers no)
		(fp_poly
			(pts
				(arc
					(start 0.3556 0)
					(mid -0.3556 0)
					(end 0.3556 0)
				)
			)
			(stroke
				(width 0)
				(type default)
			)
			(fill no)
			(layer "B.CrtYd")
		)
		(fp_poly
			(pts
				(arc
					(start 0.6096 0)
					(mid -0.6096 0)
					(end 0.6096 0)
				)
			)
			(stroke
				(width 0)
				(type default)
			)
			(fill no)
			(layer "B.Fab")
		)
		(pad "1" smd circle
			(at 0 0 180)
			(size 0.7112 0.7112)
			(layers "B.Cu" "B.Mask" "B.Paste")
			(net "SPARE5")
		)
	)
)
